# SCM (Grand Teton) — schematic netlist excerpt (pin names and nets, part order shuffled) for the footprints in the layout excerpt that follows; sources: Cadence DE-HDL packaged netlist, KiCad conversion of 12092022_DA0F0TMDCD0_F0T_Management_Board_D_brd_V3_OCP.brd

D6  Q_LED  IC  pkg SMLF  page 47 : A = LED_POSTCODE_6_R ; C = GND
C272  Q_CAP  0.1UF 25V 10% X7R  pkg 0402  page 12 : A = P2E_GPU_TX_DP ; B = P2E_GPU_TX_C_DP

(kicad_pcb
	(version 20260206)
	(generator "pcbnew")
	(generator_version "10.0")
	(general
		(thickness 1.6)
		(legacy_teardrops no)
	)
	(paper "A4")
	(title_block
		(title "12092022_DA0F0TMDCD0_F0T_Management_Board_D_brd_V3_OCP.brd")
		(comment 1 "Grand Teton / footprints 694-695 of 1440")
	)
	(layers
		(0 "F.Cu" signal "TOP")
		(4 "In1.Cu" signal "GND")
		(6 "In2.Cu" signal "IN1")
		(8 "In3.Cu" signal "GND1")
		(10 "In4.Cu" signal "IN2")
		(12 "In5.Cu" signal "VCC")
		(14 "In6.Cu" signal "VCC1")
		(16 "In7.Cu" signal "IN3")
		(18 "In8.Cu" signal "GND2")
		(20 "In9.Cu" signal "IN4")
		(22 "In10.Cu" signal "GND3")
		(2 "B.Cu" signal "BOTTOM")
		(9 "F.Adhes" user "F.Adhesive")
		(11 "B.Adhes" user "B.Adhesive")
		(13 "F.Paste" user "Package Geometry/Pastemask Top")
		(15 "B.Paste" user "Package Geometry/Pastemask Bottom")
		(5 "F.SilkS" user "Ref Des/Silkscreen Top")
		(7 "B.SilkS" user "Ref Des/Silkscreen Bottom")
		(1 "F.Mask" user "Board Geometry/Soldermask Top")
		(3 "B.Mask" user "Board Geometry/Soldermask Bottom")
		(17 "Dwgs.User" user "User.Drawings")
		(19 "Cmts.User" user "User.Comments")
		(21 "Eco1.User" user "User.Eco1")
		(23 "Eco2.User" user "User.Eco2")
		(25 "Edge.Cuts" user "Board Geometry/Outline")
		(27 "Margin" user)
		(31 "F.CrtYd" user "Package Geometry/Place Bound Top")
		(29 "B.CrtYd" user "Package Geometry/Place Bound Bottom")
		(35 "F.Fab" user "Ref Des/Assembly Top")
		(33 "B.Fab" user "Ref Des/Assembly Bottom")
	)
	(footprint ""
		(layer "F.Cu")
		(at 75.646534 -31.764986 -90)
		(property "Reference" "D6"
			(at 4.129786 -8.123936 90)
			(unlocked yes)
			(layer "F.SilkS")
			(effects
				(font
					(size 0.7874 0.5842)
					(thickness 0.1524)
				)
				(justify left)
			)
		)
		(property "Value" ""
			(at 0 0 270)
			(layer "F.Fab")
			(effects
				(font
					(size 1.27 1.27)
				)
			)
		)
		(duplicate_pad_numbers_are_jumpers no)
		(fp_line
			(start -1.3208 0.5588)
			(end -1.3208 -0.5588)
			(stroke
				(width 0.1524)
				(type default)
			)
			(layer "F.SilkS")
		)
		(fp_line
			(start 1.3208 0.5588)
			(end -1.3208 0.5588)
			(stroke
				(width 0.1524)
				(type default)
			)
			(layer "F.SilkS")
		)
		(fp_line
			(start 1.6256 0.5588)
			(end 1.6256 -0.5588)
			(stroke
				(width 0.1524)
				(type default)
			)
			(layer "F.SilkS")
		)
		(fp_line
			(start 1.778 0.5588)
			(end 1.3208 0.5588)
			(stroke
				(width 0.1524)
				(type default)
			)
			(layer "F.SilkS")
		)
		(fp_line
			(start -1.3208 -0.5588)
			(end 1.3208 -0.5588)
			(stroke
				(width 0.1524)
				(type default)
			)
			(layer "F.SilkS")
		)
		(fp_line
			(start 1.3208 -0.5588)
			(end 1.3208 0.5588)
			(stroke
				(width 0.1524)
				(type default)
			)
			(layer "F.SilkS")
		)
		(fp_line
			(start 1.4732 -0.5588)
			(end 1.4732 0.5588)
			(stroke
				(width 0.1524)
				(type default)
			)
			(layer "F.SilkS")
		)
		(fp_line
			(start 1.778 -0.5588)
			(end 1.778 0.5588)
			(stroke
				(width 0.1524)
				(type default)
			)
			(layer "F.SilkS")
		)
		(fp_line
			(start 1.778 -0.5588)
			(end 1.3208 -0.5588)
			(stroke
				(width 0.1524)
				(type default)
			)
			(layer "F.SilkS")
		)
		(fp_line
			(start -0.8001 0.40005)
			(end -0.8001 -0.40005)
			(stroke
				(width 0.1)
				(type default)
			)
			(layer "F.Fab")
		)
		(fp_line
			(start 0.8001 0.40005)
			(end -0.8001 0.40005)
			(stroke
				(width 0.1)
				(type default)
			)
			(layer "F.Fab")
		)
		(fp_line
			(start -0.8001 -0.40005)
			(end 0.8001 -0.40005)
			(stroke
				(width 0.1)
				(type default)
			)
			(layer "F.Fab")
		)
		(fp_line
			(start 0.8001 -0.40005)
			(end 0.8001 0.40005)
			(stroke
				(width 0.1)
				(type default)
			)
			(layer "F.Fab")
		)
		(fp_text user "+"
			(at -1.718564 -0.604266 180)
			(unlocked yes)
			(layer "F.SilkS")
			(effects
				(font
					(size 1.905 1.4224)
					(thickness 0.1524)
				)
				(justify left)
			)
		)
		(fp_text user "-"
			(at 0.472186 -1.029716 270)
			(unlocked yes)
			(layer "F.SilkS")
			(effects
				(font
					(size 1.905 1.4224)
					(thickness 0.1524)
				)
				(justify left)
			)
		)
		(fp_text user "+"
			(at -2.5654 -0.22225 270)
			(unlocked yes)
			(layer "F.Fab")
			(effects
				(font
					(size 1.905 1.4224)
					(thickness 0.1524)
				)
				(justify left)
			)
		)
		(fp_text user "-"
			(at 1.6256 -0.22225 270)
			(unlocked yes)
			(layer "F.Fab")
			(effects
				(font
					(size 1.905 1.4224)
					(thickness 0.1524)
				)
				(justify left)
			)
		)
		(pad "A" smd rect
			(at -0.750062 0 270)
			(size 0.8128 0.8128)
			(layers "F.Cu" "F.Mask" "F.Paste")
			(net "LED_POSTCODE_6_R")
		)
		(pad "C" smd rect
			(at 0.750062 0 270)
			(size 0.8128 0.8128)
			(layers "F.Cu" "F.Mask" "F.Paste")
			(net "GND")
		)
	)
	(footprint ""
		(layer "F.Cu")
		(at 14.351 -109.347 90)
		(property "Reference" "C272"
			(at 0 0 90)
			(layer "F.SilkS")
			(hide yes)
			(effects
				(font
					(size 1.27 1.27)
				)
			)
		)
		(property "Value" ""
			(at 0 0 90)
			(layer "F.Fab")
			(effects
				(font
					(size 1.27 1.27)
				)
			)
		)
		(duplicate_pad_numbers_are_jumpers no)
		(fp_line
			(start -0.4572 -0.4064)
			(end 0.381 -0.4064)
			(stroke
				(width 0.1524)
				(type default)
			)
			(layer "F.SilkS")
		)
		(fp_line
			(start 0.7874 0.0254)
			(end 0.7874 0.4064)
			(stroke
				(width 0.1524)
				(type default)
			)
			(layer "F.SilkS")
		)
		(fp_line
			(start 0.7874 0.4064)
			(end -0.7874 0.4064)
			(stroke
				(width 0.1524)
				(type default)
			)
			(layer "F.SilkS")
		)
		(fp_line
			(start -0.7874 0.4064)
			(end -0.7874 0.0254)
			(stroke
				(width 0.1524)
				(type default)
			)
			(layer "F.SilkS")
		)
		(fp_line
			(start -0.12065 -0.305054)
			(end -0.12065 -0.2794)
			(stroke
				(width 0.1)
				(type default)
			)
			(layer "F.Fab")
		)
		(fp_line
			(start -0.67945 -0.305054)
			(end -0.12065 -0.305054)
			(stroke
				(width 0.1)
				(type default)
			)
			(layer "F.Fab")
		)
		(fp_line
			(start 0.67945 -0.3048)
			(end 0.67945 0.3048)
			(stroke
				(width 0.1)
				(type default)
			)
			(layer "F.Fab")
		)
		(fp_line
			(start 0.12065 -0.3048)
			(end 0.67945 -0.3048)
			(stroke
				(width 0.1)
				(type default)
			)
			(layer "F.Fab")
		)
		(fp_line
			(start 0.12065 -0.2794)
			(end 0.12065 -0.3048)
			(stroke
				(width 0.1)
				(type default)
			)
			(layer "F.Fab")
		)
		(fp_line
			(start -0.12065 -0.2794)
			(end 0.12065 -0.2794)
			(stroke
				(width 0.1)
				(type default)
			)
			(layer "F.Fab")
		)
		(fp_line
			(start 0.120396 0.2794)
			(end -0.12065 0.2794)
			(stroke
				(width 0.1)
				(type default)
			)
			(layer "F.Fab")
		)
		(fp_line
			(start -0.12065 0.2794)
			(end -0.12065 0.3048)
			(stroke
				(width 0.1)
				(type default)
			)
			(layer "F.Fab")
		)
		(fp_line
			(start 0.67945 0.3048)
			(end 0.120396 0.3048)
			(stroke
				(width 0.1)
				(type default)
			)
			(layer "F.Fab")
		)
		(fp_line
			(start 0.120396 0.3048)
			(end 0.120396 0.2794)
			(stroke
				(width 0.1)
				(type default)
			)
			(layer "F.Fab")
		)
		(fp_line
			(start -0.12065 0.3048)
			(end -0.67945 0.3048)
			(stroke
				(width 0.1)
				(type default)
			)
			(layer "F.Fab")
		)
		(fp_line
			(start -0.67945 0.3048)
			(end -0.67945 -0.305054)
			(stroke
				(width 0.1)
				(type default)
			)
			(layer "F.Fab")
		)
		(pad "1" smd circle
			(at -0.40005 0 90)
			(size 0 0)
			(layers "F.Cu" "F.Mask" "F.Paste")
			(net "P2E_GPU_TX_DP")
		)
		(pad "2" smd circle
			(at 0.40005 0 90)
			(size 0 0)
			(layers "F.Cu" "F.Mask" "F.Paste")
			(net "P2E_GPU_TX_C_DP")
		)
	)
)
